(kicad_pcb
	(version 20260206)
	(generator "pcbnew")
	(generator_version "10.0")
	(general
		(thickness 1.6)
		(legacy_teardrops no)
	)
	(paper "A4")
	(title_block
		(title "Bryce Canyon_IOM_IOC_16318-2_OCP.brd")
		(comment 1 "Bryce Canyon / footprints 770-777 of 1605")
	)
	(layers
		(0 "F.Cu" signal "TOP")
		(4 "In1.Cu" signal "L2GND")
		(6 "In2.Cu" signal "L3")
		(8 "In3.Cu" signal "L4VCC")
		(10 "In4.Cu" signal "L5VCC")
		(12 "In5.Cu" signal "L6")
		(14 "In6.Cu" signal "L7GND")
		(2 "B.Cu" signal "BOTTOM")
		(9 "F.Adhes" user "F.Adhesive")
		(11 "B.Adhes" user "B.Adhesive")
		(13 "F.Paste" user "Package Geometry/Pastemask Top")
		(15 "B.Paste" user "Package Geometry/Pastemask Bottom")
		(5 "F.SilkS" user "Ref Des/Silkscreen Top")
		(7 "B.SilkS" user "Ref Des/Silkscreen Bottom")
		(1 "F.Mask" user "Board Geometry/Soldermask Top")
		(3 "B.Mask" user "Board Geometry/Soldermask Bottom")
		(17 "Dwgs.User" user "User.Drawings")
		(19 "Cmts.User" user "User.Comments")
		(21 "Eco1.User" user "User.Eco1")
		(23 "Eco2.User" user "User.Eco2")
		(25 "Edge.Cuts" user "Board Geometry/Outline")
		(27 "Margin" user)
		(31 "F.CrtYd" user "Package Geometry/Place Bound Top")
		(29 "B.CrtYd" user "Package Geometry/Place Bound Bottom")
		(35 "F.Fab" user "Ref Des/Assembly Top")
		(33 "B.Fab" user "Ref Des/Assembly Bottom")
	)
	(footprint ""
		(layer "F.Cu")
		(at 37.299646 -173.66361 90)
		(property "Reference" "R496"
			(at 0 0 90)
			(layer "F.SilkS")
			(hide yes)
			(effects
				(font
					(size 1.27 1.27)
				)
			)
		)
		(property "Value" "44K2R2F-1-GP"
			(at 0.064008 -3.993896 90)
			(unlocked yes)
			(layer "F.Fab")
			(hide yes)
			(effects
				(font
					(size 1.016 1.016)
					(thickness 0.1524)
				)
			)
		)
		(property "Device Type" "R402H16"
			(at 0.064008 -5.517896 90)
			(unlocked yes)
			(layer "F.Fab")
			(hide yes)
			(effects
				(font
					(size 1.016 1.016)
					(thickness 0.1524)
				)
			)
		)
		(duplicate_pad_numbers_are_jumpers no)
		(fp_line
			(start 0.508 -0.9398)
			(end -0.508 -0.9398)
			(stroke
				(width 0.1524)
				(type default)
			)
			(layer "F.SilkS")
		)
		(fp_line
			(start -0.508 -0.9398)
			(end -0.508 0.9398)
			(stroke
				(width 0.1524)
				(type default)
			)
			(layer "F.SilkS")
		)
		(fp_rect
			(start -0.508 0.9398)
			(end 0.508 -0.9398)
			(stroke
				(width 0)
				(type default)
			)
			(fill no)
			(layer "F.CrtYd")
		)
		(fp_rect
			(start -0.508 0.9398)
			(end 0.508 -0.9398)
			(stroke
				(width 0)
				(type default)
			)
			(fill no)
			(layer "F.Fab")
		)
		(pad "1" smd custom
			(at 0 -0.4445 90)
			(size 0.1397 0.1397)
			(layers "F.Cu" "F.Mask" "F.Paste")
			(net "P3V3_STBY_VFB")
			(options
				(clearance outline)
				(anchor circle)
			)
			(primitives
				(gr_poly
					(pts
						(arc
							(start -0.1778 -0.2794)
							(mid -0.249642 -0.249642)
							(end -0.2794 -0.1778)
						)
						(arc
							(start -0.2794 0.1778)
							(mid -0.249642 0.249642)
							(end -0.1778 0.2794)
						)
						(arc
							(start 0.1778 0.2794)
							(mid 0.249642 0.249642)
							(end 0.2794 0.1778)
						)
						(arc
							(start 0.2794 -0.1778)
							(mid 0.249642 -0.249642)
							(end 0.1778 -0.2794)
						)
					)
					(width 0)
					(fill yes)
				)
			)
		)
		(pad "2" smd custom
			(at 0 0.4445 90)
			(size 0.1397 0.1397)
			(layers "F.Cu" "F.Mask" "F.Paste")
			(net "P3V3_STBY_VFB_R")
			(options
				(clearance outline)
				(anchor circle)
			)
			(primitives
				(gr_poly
					(pts
						(arc
							(start -0.1778 -0.2794)
							(mid -0.249642 -0.249642)
							(end -0.2794 -0.1778)
						)
						(arc
							(start -0.2794 0.1778)
							(mid -0.249642 0.249642)
							(end -0.1778 0.2794)
						)
						(arc
							(start 0.1778 0.2794)
							(mid 0.249642 0.249642)
							(end 0.2794 0.1778)
						)
						(arc
							(start 0.2794 -0.1778)
							(mid 0.249642 -0.249642)
							(end 0.1778 -0.2794)
						)
					)
					(width 0)
					(fill yes)
				)
			)
		)
	)
	(footprint ""
		(layer "F.Cu")
		(at 214.122 -72.39 -45)
		(property "Reference" "VIA44"
			(at 0 0 315)
			(layer "F.SilkS")
			(hide yes)
			(effects
				(font
					(size 1.27 1.27)
				)
			)
		)
		(property "Value" "100OHM-8L-1D6MM-L18L16-GP"
			(at -3.721059 -4.508373 315)
			(unlocked yes)
			(layer "F.Fab")
			(hide yes)
			(effects
				(font
					(size 1.016 1.016)
					(thickness 0.1524)
				)
			)
		)
		(property "Device Type" "VIA-PCIE-4P-394076"
			(at -3.721059 -6.032502 315)
			(unlocked yes)
			(layer "F.Fab")
			(hide yes)
			(effects
				(font
					(size 1.016 1.016)
					(thickness 0.1524)
				)
			)
		)
		(duplicate_pad_numbers_are_jumpers no)
		(fp_poly
			(pts
				(xy -1.968472 -0.380877) (xy 1.968528 -0.380878) (xy 1.968527 0.381122) (xy -1.968472 0.381122)
			)
			(stroke
				(width 0)
				(type default)
			)
			(fill no)
			(layer "F.CrtYd")
		)
		(fp_poly
			(pts
				(xy -1.968472 -0.380877) (xy 1.968528 -0.380878) (xy 1.968527 0.381122) (xy -1.968472 0.381122)
			)
			(stroke
				(width 0)
				(type default)
			)
			(fill no)
			(layer "F.Fab")
		)
		(pad "1" thru_hole circle
			(at -1.5875 0 315)
			(size 0.508 0.508)
			(drill 0.254)
			(layers "*.Cu" "*.Mask")
			(remove_unused_layers no)
			(net "GND")
			(clearance 0.127)
			(thermal_gap 0.127)
		)
		(pad "2" thru_hole circle
			(at -0.571501 0 315)
			(size 0.508 0.508)
			(drill 0.254)
			(layers "*.Cu" "*.Mask")
			(remove_unused_layers no)
			(net "PHY_IOC_TO_CON_A_3_DP")
			(clearance 0.127)
			(thermal_gap 0.127)
		)
		(pad "3" thru_hole circle
			(at 0.571501 0 315)
			(size 0.508 0.508)
			(drill 0.254)
			(layers "*.Cu" "*.Mask")
			(remove_unused_layers no)
			(net "PHY_IOC_TO_CON_A_3_DN")
			(clearance 0.127)
			(thermal_gap 0.127)
		)
		(pad "4" thru_hole circle
			(at 1.5875 0 315)
			(size 0.508 0.508)
			(drill 0.254)
			(layers "*.Cu" "*.Mask")
			(remove_unused_layers no)
			(net "GND")
			(clearance 0.127)
			(thermal_gap 0.127)
		)
	)
	(footprint ""
		(layer "F.Cu")
		(at 194.437 -122.8852 90)
		(property "Reference" "C282"
			(at 0 0 90)
			(layer "F.SilkS")
			(hide yes)
			(effects
				(font
					(size 1.27 1.27)
				)
			)
		)
		(property "Value" "SC1U25V3KX-GP"
			(at 0 -2.8194 90)
			(unlocked yes)
			(layer "F.Fab")
			(hide yes)
			(effects
				(font
					(size 1.016 1.016)
					(thickness 0.1524)
				)
			)
		)
		(property "Device Type" "C603H36"
			(at 0 -4.3434 90)
			(unlocked yes)
			(layer "F.Fab")
			(hide yes)
			(effects
				(font
					(size 1.016 1.016)
					(thickness 0.1524)
				)
			)
		)
		(duplicate_pad_numbers_are_jumpers no)
		(fp_line
			(start 0.508 0)
			(end -0.508 0)
			(stroke
				(width 0.2032)
				(type default)
			)
			(layer "F.SilkS")
		)
		(fp_rect
			(start -0.5842 1.3335)
			(end 0.5842 -1.3335)
			(stroke
				(width 0)
				(type default)
			)
			(fill no)
			(layer "F.CrtYd")
		)
		(fp_rect
			(start -0.5842 1.3335)
			(end 0.5842 -1.3335)
			(stroke
				(width 0)
				(type default)
			)
			(fill no)
			(layer "F.Fab")
		)
		(pad "1" smd custom
			(at 0 -0.762 90)
			(size 0.2159 0.2159)
			(layers "F.Cu" "F.Mask" "F.Paste")
			(net "VT235_VDDL")
			(options
				(clearance outline)
				(anchor circle)
			)
			(primitives
				(gr_poly
					(pts
						(arc
							(start -0.3302 -0.4318)
							(mid -0.402042 -0.402042)
							(end -0.4318 -0.3302)
						)
						(arc
							(start -0.4318 0.3302)
							(mid -0.402042 0.402042)
							(end -0.3302 0.4318)
						)
						(arc
							(start 0.3302 0.4318)
							(mid 0.402042 0.402042)
							(end 0.4318 0.3302)
						)
						(arc
							(start 0.4318 -0.3302)
							(mid 0.402042 -0.402042)
							(end 0.3302 -0.4318)
						)
					)
					(width 0)
					(fill yes)
				)
			)
		)
		(pad "2" smd custom
			(at 0 0.762 90)
			(size 0.2159 0.2159)
			(layers "F.Cu" "F.Mask" "F.Paste")
			(net "GND")
			(options
				(clearance outline)
				(anchor circle)
			)
			(primitives
				(gr_poly
					(pts
						(arc
							(start -0.3302 -0.4318)
							(mid -0.402042 -0.402042)
							(end -0.4318 -0.3302)
						)
						(arc
							(start -0.4318 0.3302)
							(mid -0.402042 0.402042)
							(end -0.3302 0.4318)
						)
						(arc
							(start 0.3302 0.4318)
							(mid 0.402042 0.402042)
							(end 0.4318 0.3302)
						)
						(arc
							(start 0.4318 -0.3302)
							(mid 0.402042 -0.402042)
							(end 0.3302 -0.4318)
						)
					)
					(width 0)
					(fill yes)
				)
			)
		)
	)
	(footprint ""
		(layer "F.Cu")
		(at 211.464144 -63.520574 -45)
		(property "Reference" "VIA48"
			(at 0 0 315)
			(layer "F.SilkS")
			(hide yes)
			(effects
				(font
					(size 1.27 1.27)
				)
			)
		)
		(property "Value" "100OHM-8L-1D6MM-L18L16-GP"
			(at -3.721059 -4.508373 315)
			(unlocked yes)
			(layer "F.Fab")
			(hide yes)
			(effects
				(font
					(size 1.016 1.016)
					(thickness 0.1524)
				)
			)
		)
		(property "Device Type" "VIA-PCIE-4P-394076"
			(at -3.721239 -6.032322 315)
			(unlocked yes)
			(layer "F.Fab")
			(hide yes)
			(effects
				(font
					(size 1.016 1.016)
					(thickness 0.1524)
				)
			)
		)
		(duplicate_pad_numbers_are_jumpers no)
		(fp_poly
			(pts
				(xy -1.968472 -0.380877) (xy 1.968528 -0.380878) (xy 1.968527 0.381122) (xy -1.968472 0.381122)
			)
			(stroke
				(width 0)
				(type default)
			)
			(fill no)
			(layer "F.CrtYd")
		)
		(fp_poly
			(pts
				(xy -1.968472 -0.380877) (xy 1.968528 -0.380878) (xy 1.968527 0.381122) (xy -1.968472 0.381122)
			)
			(stroke
				(width 0)
				(type default)
			)
			(fill no)
			(layer "F.Fab")
		)
		(pad "1" thru_hole circle
			(at -1.5875 0 315)
			(size 0.508 0.508)
			(drill 0.254)
			(layers "*.Cu" "*.Mask")
			(remove_unused_layers no)
			(net "GND")
			(clearance 0.127)
			(thermal_gap 0.127)
		)
		(pad "2" thru_hole circle
			(at -0.571501 0 315)
			(size 0.508 0.508)
			(drill 0.254)
			(layers "*.Cu" "*.Mask")
			(remove_unused_layers no)
			(net "PHY_IOC_TO_CON_B_3_DP")
			(clearance 0.127)
			(thermal_gap 0.127)
		)
		(pad "3" thru_hole circle
			(at 0.571501 0 315)
			(size 0.508 0.508)
			(drill 0.254)
			(layers "*.Cu" "*.Mask")
			(remove_unused_layers no)
			(net "PHY_IOC_TO_CON_B_3_DN")
			(clearance 0.127)
			(thermal_gap 0.127)
		)
		(pad "4" thru_hole circle
			(at 1.5875 0 315)
			(size 0.508 0.508)
			(drill 0.254)
			(layers "*.Cu" "*.Mask")
			(remove_unused_layers no)
			(net "GND")
			(clearance 0.127)
			(thermal_gap 0.127)
		)
	)
	(footprint ""
		(layer "F.Cu")
		(at 82.296 -149.733 90)
		(property "Reference" "U102"
			(at 0 0 90)
			(layer "F.SilkS")
			(hide yes)
			(effects
				(font
					(size 1.27 1.27)
				)
			)
		)
		(property "Value" "SN74LVC1G14DCKR-GP"
			(at -2.3368 -8.6868 90)
			(unlocked yes)
			(layer "F.Fab")
			(hide yes)
			(effects
				(font
					(size 1.016 1.016)
					(thickness 0.1524)
				)
			)
		)
		(property "Device Type" "SC70-5H44"
			(at -2.3114 -10.414 90)
			(unlocked yes)
			(layer "F.Fab")
			(hide yes)
			(effects
				(font
					(size 1.016 1.016)
					(thickness 0.1524)
				)
			)
		)
		(duplicate_pad_numbers_are_jumpers no)
		(fp_line
			(start 1.3843 -1.8034)
			(end 1.3843 -1.1176)
			(stroke
				(width 0.3302)
				(type default)
			)
			(layer "F.SilkS")
		)
		(fp_line
			(start 0.6604 -1.8034)
			(end 1.3843 -1.8034)
			(stroke
				(width 0.3302)
				(type default)
			)
			(layer "F.SilkS")
		)
		(fp_line
			(start 1.27 -1.7018)
			(end 1.27 1.7018)
			(stroke
				(width 0.1524)
				(type default)
			)
			(layer "F.SilkS")
		)
		(fp_line
			(start -1.27 -1.7018)
			(end 1.27 -1.7018)
			(stroke
				(width 0.1524)
				(type default)
			)
			(layer "F.SilkS")
		)
		(fp_line
			(start 1.27 1.7018)
			(end -1.27 1.7018)
			(stroke
				(width 0.1524)
				(type default)
			)
			(layer "F.SilkS")
		)
		(fp_line
			(start -1.27 1.7018)
			(end -1.27 -1.7018)
			(stroke
				(width 0.1524)
				(type default)
			)
			(layer "F.SilkS")
		)
		(fp_rect
			(start -1.524 1.9558)
			(end 1.524 -1.9558)
			(stroke
				(width 0)
				(type default)
			)
			(fill no)
			(layer "F.CrtYd")
		)
		(fp_poly
			(pts
				(xy -1.524 -1.9558) (xy 1.524 -1.9558) (xy 1.524 1.9558) (xy -1.524 1.9558)
			)
			(stroke
				(width 0)
				(type default)
			)
			(fill no)
			(layer "F.Fab")
		)
		(pad "1" smd rect
			(at 0.65024 -0.8255 90)
			(size 0.4064 1.2192)
			(layers "F.Cu" "F.Mask" "F.Paste")
			(net "Net_23")
		)
		(pad "2" smd rect
			(at 0 -0.8255 90)
			(size 0.4064 1.2192)
			(layers "F.Cu" "F.Mask" "F.Paste")
			(net "COMP_TO_BMC_RESET_R")
		)
		(pad "3" smd rect
			(at -0.65024 -0.8255 90)
			(size 0.4064 1.2192)
			(layers "F.Cu" "F.Mask" "F.Paste")
			(net "GND")
		)
		(pad "4" smd rect
			(at -0.65024 0.8255 90)
			(size 0.4064 1.2192)
			(layers "F.Cu" "F.Mask" "F.Paste")
			(net "COMP_TO_BMC_RESET_N_OUT")
		)
		(pad "5" smd rect
			(at 0.65024 0.8255 90)
			(size 0.4064 1.2192)
			(layers "F.Cu" "F.Mask" "F.Paste")
			(net "P3V3_STBY")
		)
	)
	(footprint ""
		(layer "F.Cu")
		(at 18.05686 -14.6812 180)
		(property "Reference" "C528"
			(at 0 0 180)
			(layer "F.SilkS")
			(hide yes)
			(effects
				(font
					(size 1.27 1.27)
				)
			)
		)
		(property "Value" "SC1000P2KV6KX-GP-U"
			(at 0.0508 -3.5052 180)
			(unlocked yes)
			(layer "F.Fab")
			(hide yes)
			(effects
				(font
					(size 1.016 1.016)
					(thickness 0.1524)
				)
			)
		)
		(property "Device Type" "C1206H58"
			(at 0.0508 -5.0292 180)
			(unlocked yes)
			(layer "F.Fab")
			(hide yes)
			(effects
				(font
					(size 1.016 1.016)
					(thickness 0.1524)
				)
			)
		)
		(duplicate_pad_numbers_are_jumpers no)
		(fp_line
			(start 1.016 2.2352)
			(end -1.016 2.2352)
			(stroke
				(width 0.1524)
				(type default)
			)
			(layer "F.SilkS")
		)
		(fp_line
			(start 1.016 0.8382)
			(end 1.016 2.2352)
			(stroke
				(width 0.1524)
				(type default)
			)
			(layer "F.SilkS")
		)
		(fp_line
			(start 1.016 -2.2352)
			(end 1.016 -0.8382)
			(stroke
				(width 0.1524)
				(type default)
			)
			(layer "F.SilkS")
		)
		(fp_line
			(start 1.016 -2.2352)
			(end -1.016 -2.2352)
			(stroke
				(width 0.1524)
				(type default)
			)
			(layer "F.SilkS")
		)
		(fp_line
			(start -1.016 2.2352)
			(end -1.016 0.8128)
			(stroke
				(width 0.1524)
				(type default)
			)
			(layer "F.SilkS")
		)
		(fp_line
			(start -1.016 -2.2352)
			(end -1.016 -0.8382)
			(stroke
				(width 0.1524)
				(type default)
			)
			(layer "F.SilkS")
		)
		(fp_rect
			(start -1.0922 2.3114)
			(end 1.0922 -2.3114)
			(stroke
				(width 0)
				(type default)
			)
			(fill no)
			(layer "F.CrtYd")
		)
		(fp_poly
			(pts
				(xy -1.0922 -2.3114) (xy 1.0922 -2.3114) (xy 1.0922 2.3114) (xy -1.0922 2.3114)
			)
			(stroke
				(width 0)
				(type default)
			)
			(fill no)
			(layer "F.Fab")
		)
		(pad "1" smd rect
			(at 0 -1.397 180)
			(size 1.651 1.27)
			(layers "F.Cu" "F.Mask" "F.Paste")
			(net "PWR_BTN_GND")
		)
		(pad "2" smd rect
			(at 0 1.397 180)
			(size 1.651 1.27)
			(layers "F.Cu" "F.Mask" "F.Paste")
			(net "GND")
		)
	)
	(footprint ""
		(layer "F.Cu")
		(at 194.85229 -105.784142)
		(property "Reference" "C266"
			(at 0 0 0)
			(layer "F.SilkS")
			(hide yes)
			(effects
				(font
					(size 1.27 1.27)
				)
			)
		)
		(property "Value" "SC22U6D3V6KX-2-GP"
			(at -0.0762 -5.1308 0)
			(unlocked yes)
			(layer "F.Fab")
			(hide yes)
			(effects
				(font
					(size 1.016 1.016)
					(thickness 0.1524)
				)
			)
		)
		(property "Device Type" "C1206H71"
			(at -0.127 -6.6548 0)
			(unlocked yes)
			(layer "F.Fab")
			(hide yes)
			(effects
				(font
					(size 1.016 1.016)
					(thickness 0.1524)
				)
			)
		)
		(duplicate_pad_numbers_are_jumpers no)
		(fp_line
			(start -1.016 -2.2352)
			(end 1.016 -2.2352)
			(stroke
				(width 0.1524)
				(type default)
			)
			(layer "F.SilkS")
		)
		(fp_line
			(start -1.016 -0.8382)
			(end -1.016 -2.2352)
			(stroke
				(width 0.1524)
				(type default)
			)
			(layer "F.SilkS")
		)
		(fp_line
			(start -1.016 2.2352)
			(end -1.016 0.8382)
			(stroke
				(width 0.1524)
				(type default)
			)
			(layer "F.SilkS")
		)
		(fp_line
			(start 1.016 -2.2352)
			(end 1.016 -0.8382)
			(stroke
				(width 0.1524)
				(type default)
			)
			(layer "F.SilkS")
		)
		(fp_line
			(start 1.016 0.8382)
			(end 1.016 2.2352)
			(stroke
				(width 0.1524)
				(type default)
			)
			(layer "F.SilkS")
		)
		(fp_line
			(start 1.016 2.2352)
			(end -1.016 2.2352)
			(stroke
				(width 0.1524)
				(type default)
			)
			(layer "F.SilkS")
		)
		(fp_rect
			(start -1.0922 2.3114)
			(end 1.0922 -2.3114)
			(stroke
				(width 0)
				(type default)
			)
			(fill no)
			(layer "F.CrtYd")
		)
		(fp_poly
			(pts
				(xy 1.0922 -2.3114) (xy 1.0922 2.3114) (xy -1.0922 2.3114) (xy -1.0922 -2.3114)
			)
			(stroke
				(width 0)
				(type default)
			)
			(fill no)
			(layer "F.Fab")
		)
		(pad "1" smd rect
			(at 0 -1.397)
			(size 1.651 1.27)
			(layers "F.Cu" "F.Mask" "F.Paste")
			(net "P0V975")
		)
		(pad "2" smd rect
			(at 0 1.397)
			(size 1.651 1.27)
			(layers "F.Cu" "F.Mask" "F.Paste")
			(net "GND")
		)
	)
	(footprint ""
		(layer "F.Cu")
		(at 11.04392 -12.9413 180)
		(property "Reference" "C31"
			(at 0 0 180)
			(layer "F.SilkS")
			(hide yes)
			(effects
				(font
					(size 1.27 1.27)
				)
			)
		)
		(property "Value" "SC1U16V3KX-5GP"
			(at 0 -2.8194 180)
			(unlocked yes)
			(layer "F.Fab")
			(hide yes)
			(effects
				(font
					(size 1.016 1.016)
					(thickness 0.1524)
				)
			)
		)
		(property "Device Type" "C603H36"
			(at 0 -4.3434 180)
			(unlocked yes)
			(layer "F.Fab")
			(hide yes)
			(effects
				(font
					(size 1.016 1.016)
					(thickness 0.1524)
				)
			)
		)
		(duplicate_pad_numbers_are_jumpers no)
		(fp_line
			(start 0.508 0)
			(end -0.508 0)
			(stroke
				(width 0.2032)
				(type default)
			)
			(layer "F.SilkS")
		)
		(fp_rect
			(start -0.5842 1.3335)
			(end 0.5842 -1.3335)
			(stroke
				(width 0)
				(type default)
			)
			(fill no)
			(layer "F.CrtYd")
		)
		(fp_rect
			(start -0.5842 1.3335)
			(end 0.5842 -1.3335)
			(stroke
				(width 0)
				(type default)
			)
			(fill no)
			(layer "F.Fab")
		)
		(pad "1" smd custom
			(at 0 -0.762 180)
			(size 0.2159 0.2159)
			(layers "F.Cu" "F.Mask" "F.Paste")
			(net "SYS_RST_BTN_IN_N")
			(options
				(clearance outline)
				(anchor circle)
			)
			(primitives
				(gr_poly
					(pts
						(arc
							(start -0.3302 -0.4318)
							(mid -0.402042 -0.402042)
							(end -0.4318 -0.3302)
						)
						(arc
							(start -0.4318 0.3302)
							(mid -0.402042 0.402042)
							(end -0.3302 0.4318)
						)
						(arc
							(start 0.3302 0.4318)
							(mid 0.402042 0.402042)
							(end 0.4318 0.3302)
						)
						(arc
							(start 0.4318 -0.3302)
							(mid 0.402042 -0.402042)
							(end 0.3302 -0.4318)
						)
					)
					(width 0)
					(fill yes)
				)
			)
		)
		(pad "2" smd custom
			(at 0 0.762 180)
			(size 0.2159 0.2159)
			(layers "F.Cu" "F.Mask" "F.Paste")
			(net "GND")
			(options
				(clearance outline)
				(anchor circle)
			)
			(primitives
				(gr_poly
					(pts
						(arc
							(start -0.3302 -0.4318)
							(mid -0.402042 -0.402042)
							(end -0.4318 -0.3302)
						)
						(arc
							(start -0.4318 0.3302)
							(mid -0.402042 0.402042)
							(end -0.3302 0.4318)
						)
						(arc
							(start 0.3302 0.4318)
							(mid 0.402042 0.402042)
							(end 0.4318 0.3302)
						)
						(arc
							(start 0.4318 -0.3302)
							(mid 0.402042 -0.402042)
							(end 0.3302 -0.4318)
						)
					)
					(width 0)
					(fill yes)
				)
			)
		)
	)
)
